(kicad_pcb
	(version 20260206)
	(generator "pcbnew")
	(generator_version "10.0")
	(general
		(thickness 1.6)
		(legacy_teardrops no)
	)
	(paper "A4")
	(title_block
		(title "baseboard — 13948-1b.1110WZS1818.brd")
		(comment 1 "Honey Badger (Wiwynn) / footprints 777-783 of 2523")
	)
	(layers
		(0 "F.Cu" signal "TOP")
		(4 "In1.Cu" signal "L2GND")
		(6 "In2.Cu" signal "L3")
		(8 "In3.Cu" signal "L4VCC")
		(10 "In4.Cu" signal "L5VCC")
		(12 "In5.Cu" signal "L6")
		(14 "In6.Cu" signal "L7GND")
		(2 "B.Cu" signal "BOTTOM")
		(9 "F.Adhes" user "F.Adhesive")
		(11 "B.Adhes" user "B.Adhesive")
		(13 "F.Paste" user "Package Geometry/Pastemask Top")
		(15 "B.Paste" user "Package Geometry/Pastemask Bottom")
		(5 "F.SilkS" user "Ref Des/Silkscreen Top")
		(7 "B.SilkS" user "Ref Des/Silkscreen Bottom")
		(1 "F.Mask" user "Board Geometry/Soldermask Top")
		(3 "B.Mask" user "Board Geometry/Soldermask Bottom")
		(17 "Dwgs.User" user "User.Drawings")
		(19 "Cmts.User" user "User.Comments")
		(21 "Eco1.User" user "User.Eco1")
		(23 "Eco2.User" user "User.Eco2")
		(25 "Edge.Cuts" user "Board Geometry/Outline")
		(27 "Margin" user)
		(31 "F.CrtYd" user "Package Geometry/Place Bound Top")
		(29 "B.CrtYd" user "Package Geometry/Place Bound Bottom")
		(35 "F.Fab" user "Ref Des/Assembly Top")
		(33 "B.Fab" user "Ref Des/Assembly Bottom")
	)
	(footprint ""
		(layer "F.Cu")
		(at 91.567 -242.443 180)
		(property "Reference" "SR956"
			(at 0 0 180)
			(layer "F.SilkS")
			(hide yes)
			(effects
				(font
					(size 1.27 1.27)
				)
			)
		)
		(property "Value" "4K7R2F-GP"
			(at 0.064008 -3.993896 180)
			(unlocked yes)
			(layer "F.Fab")
			(hide yes)
			(effects
				(font
					(size 1.016 1.016)
					(thickness 0.1524)
				)
			)
		)
		(property "Device Type" "R402H16"
			(at 0.064008 -5.517896 180)
			(unlocked yes)
			(layer "F.Fab")
			(hide yes)
			(effects
				(font
					(size 1.016 1.016)
					(thickness 0.1524)
				)
			)
		)
		(duplicate_pad_numbers_are_jumpers no)
		(fp_line
			(start 0.508 -0.9398)
			(end -0.508 -0.9398)
			(stroke
				(width 0.1524)
				(type default)
			)
			(layer "F.SilkS")
		)
		(fp_line
			(start -0.508 -0.9398)
			(end -0.508 0.9398)
			(stroke
				(width 0.1524)
				(type default)
			)
			(layer "F.SilkS")
		)
		(fp_rect
			(start -0.508 0.9398)
			(end 0.508 -0.9398)
			(stroke
				(width 0)
				(type default)
			)
			(fill no)
			(layer "F.CrtYd")
		)
		(fp_rect
			(start -0.508 0.9398)
			(end 0.508 -0.9398)
			(stroke
				(width 0)
				(type default)
			)
			(fill no)
			(layer "F.Fab")
		)
		(pad "1" smd custom
			(at 0 -0.4445 180)
			(size 0.1397 0.1397)
			(layers "F.Cu" "F.Mask" "F.Paste")
			(net "SAS_FAULT_LED15")
			(options
				(clearance outline)
				(anchor circle)
			)
			(primitives
				(gr_poly
					(pts
						(arc
							(start -0.1778 -0.2794)
							(mid -0.249642 -0.249642)
							(end -0.2794 -0.1778)
						)
						(arc
							(start -0.2794 0.1778)
							(mid -0.249642 0.249642)
							(end -0.1778 0.2794)
						)
						(arc
							(start 0.1778 0.2794)
							(mid 0.249642 0.249642)
							(end 0.2794 0.1778)
						)
						(arc
							(start 0.2794 -0.1778)
							(mid 0.249642 -0.249642)
							(end 0.1778 -0.2794)
						)
					)
					(width 0)
					(fill yes)
				)
			)
		)
		(pad "2" smd custom
			(at 0 0.4445 180)
			(size 0.1397 0.1397)
			(layers "F.Cu" "F.Mask" "F.Paste")
			(net "P3V3_STBY")
			(options
				(clearance outline)
				(anchor circle)
			)
			(primitives
				(gr_poly
					(pts
						(arc
							(start -0.1778 -0.2794)
							(mid -0.249642 -0.249642)
							(end -0.2794 -0.1778)
						)
						(arc
							(start -0.2794 0.1778)
							(mid -0.249642 0.249642)
							(end -0.1778 0.2794)
						)
						(arc
							(start 0.1778 0.2794)
							(mid 0.249642 0.249642)
							(end 0.2794 0.1778)
						)
						(arc
							(start 0.2794 -0.1778)
							(mid 0.249642 -0.249642)
							(end 0.1778 -0.2794)
						)
					)
					(width 0)
					(fill yes)
				)
			)
		)
	)
	(footprint ""
		(layer "F.Cu")
		(at 67.691 -54.102 180)
		(property "Reference" "SC982"
			(at 0 0 180)
			(layer "F.SilkS")
			(hide yes)
			(effects
				(font
					(size 1.27 1.27)
				)
			)
		)
		(property "Value" "SCD1U16V2KX-3GP"
			(at 1.1811 -2.7051 180)
			(unlocked yes)
			(layer "F.Fab")
			(hide yes)
			(effects
				(font
					(size 1.016 1.016)
					(thickness 0.1524)
				)
			)
		)
		(property "Device Type" "C402H22"
			(at 1.1811 -4.2291 180)
			(unlocked yes)
			(layer "F.Fab")
			(hide yes)
			(effects
				(font
					(size 1.016 1.016)
					(thickness 0.1524)
				)
			)
		)
		(duplicate_pad_numbers_are_jumpers no)
		(fp_rect
			(start -0.4318 0.9525)
			(end 0.4318 -0.9525)
			(stroke
				(width 0)
				(type default)
			)
			(fill no)
			(layer "F.CrtYd")
		)
		(fp_rect
			(start -0.4318 0.9525)
			(end 0.4318 -0.9525)
			(stroke
				(width 0)
				(type default)
			)
			(fill no)
			(layer "F.Fab")
		)
		(pad "1" smd custom
			(at 0 -0.4445 180)
			(size 0.1524 0.1524)
			(layers "F.Cu" "F.Mask" "F.Paste")
			(net "P1V8_C")
			(options
				(clearance outline)
				(anchor circle)
			)
			(primitives
				(gr_poly
					(pts
						(arc
							(start 0.3048 -0.2032)
							(mid 0.275042 -0.275042)
							(end 0.2032 -0.3048)
						)
						(arc
							(start -0.2032 -0.3048)
							(mid -0.275042 -0.275042)
							(end -0.3048 -0.2032)
						)
						(arc
							(start -0.3048 0.2032)
							(mid -0.275042 0.275042)
							(end -0.2032 0.3048)
						)
						(arc
							(start 0.2032 0.3048)
							(mid 0.275042 0.275042)
							(end 0.3048 0.2032)
						)
					)
					(width 0)
					(fill yes)
				)
			)
		)
		(pad "2" smd custom
			(at 0 0.4445 180)
			(size 0.1524 0.1524)
			(layers "F.Cu" "F.Mask" "F.Paste")
			(net "GND")
			(options
				(clearance outline)
				(anchor circle)
			)
			(primitives
				(gr_poly
					(pts
						(arc
							(start 0.3048 -0.2032)
							(mid 0.275042 -0.275042)
							(end 0.2032 -0.3048)
						)
						(arc
							(start -0.2032 -0.3048)
							(mid -0.275042 -0.275042)
							(end -0.3048 -0.2032)
						)
						(arc
							(start -0.3048 0.2032)
							(mid -0.275042 0.275042)
							(end -0.2032 0.3048)
						)
						(arc
							(start 0.2032 0.3048)
							(mid 0.275042 0.275042)
							(end 0.3048 0.2032)
						)
					)
					(width 0)
					(fill yes)
				)
			)
		)
	)
	(footprint ""
		(layer "F.Cu")
		(at 330.699872 -232.482136)
		(property "Reference" "R180"
			(at 0 0 0)
			(layer "F.SilkS")
			(hide yes)
			(effects
				(font
					(size 1.27 1.27)
				)
			)
		)
		(property "Value" "0R2J-2-GP"
			(at 0.064008 -3.993896 0)
			(unlocked yes)
			(layer "F.Fab")
			(hide yes)
			(effects
				(font
					(size 1.016 1.016)
					(thickness 0.1524)
				)
			)
		)
		(property "Device Type" "R402H16"
			(at 0.064008 -5.517896 0)
			(unlocked yes)
			(layer "F.Fab")
			(hide yes)
			(effects
				(font
					(size 1.016 1.016)
					(thickness 0.1524)
				)
			)
		)
		(duplicate_pad_numbers_are_jumpers no)
		(fp_line
			(start -0.508 -0.9398)
			(end -0.508 0.9398)
			(stroke
				(width 0.1524)
				(type default)
			)
			(layer "F.SilkS")
		)
		(fp_line
			(start 0.508 -0.9398)
			(end -0.508 -0.9398)
			(stroke
				(width 0.1524)
				(type default)
			)
			(layer "F.SilkS")
		)
		(fp_rect
			(start -0.508 0.9398)
			(end 0.508 -0.9398)
			(stroke
				(width 0)
				(type default)
			)
			(fill no)
			(layer "F.CrtYd")
		)
		(fp_rect
			(start -0.508 0.9398)
			(end 0.508 -0.9398)
			(stroke
				(width 0)
				(type default)
			)
			(fill no)
			(layer "F.Fab")
		)
		(pad "1" smd custom
			(at 0 -0.4445)
			(size 0.1397 0.1397)
			(layers "F.Cu" "F.Mask" "F.Paste")
			(net "ADC_P5V_STBY")
			(options
				(clearance outline)
				(anchor circle)
			)
			(primitives
				(gr_poly
					(pts
						(arc
							(start -0.1778 -0.2794)
							(mid -0.249642 -0.249642)
							(end -0.2794 -0.1778)
						)
						(arc
							(start -0.2794 0.1778)
							(mid -0.249642 0.249642)
							(end -0.1778 0.2794)
						)
						(arc
							(start 0.1778 0.2794)
							(mid 0.249642 0.249642)
							(end 0.2794 0.1778)
						)
						(arc
							(start 0.2794 -0.1778)
							(mid 0.249642 -0.249642)
							(end 0.1778 -0.2794)
						)
					)
					(width 0)
					(fill yes)
				)
			)
		)
		(pad "2" smd custom
			(at 0 0.4445)
			(size 0.1397 0.1397)
			(layers "F.Cu" "F.Mask" "F.Paste")
			(net "5V_STBY_SENSE")
			(options
				(clearance outline)
				(anchor circle)
			)
			(primitives
				(gr_poly
					(pts
						(arc
							(start -0.1778 -0.2794)
							(mid -0.249642 -0.249642)
							(end -0.2794 -0.1778)
						)
						(arc
							(start -0.2794 0.1778)
							(mid -0.249642 0.249642)
							(end -0.1778 0.2794)
						)
						(arc
							(start 0.1778 0.2794)
							(mid 0.249642 0.249642)
							(end 0.2794 0.1778)
						)
						(arc
							(start 0.2794 -0.1778)
							(mid 0.249642 -0.249642)
							(end 0.1778 -0.2794)
						)
					)
					(width 0)
					(fill yes)
				)
			)
		)
	)
	(footprint ""
		(layer "F.Cu")
		(at 202.888596 -120.669812 -90)
		(property "Reference" "PC228"
			(at 0 0 270)
			(layer "F.SilkS")
			(hide yes)
			(effects
				(font
					(size 1.27 1.27)
				)
			)
		)
		(property "Value" "SC1U10V2KX-1GP"
			(at 1.1811 -2.7051 270)
			(unlocked yes)
			(layer "F.Fab")
			(hide yes)
			(effects
				(font
					(size 1.016 1.016)
					(thickness 0.1524)
				)
			)
		)
		(property "Device Type" "C402H22"
			(at 1.1811 -4.2291 270)
			(unlocked yes)
			(layer "F.Fab")
			(hide yes)
			(effects
				(font
					(size 1.016 1.016)
					(thickness 0.1524)
				)
			)
		)
		(duplicate_pad_numbers_are_jumpers no)
		(fp_rect
			(start -0.4318 0.9525)
			(end 0.4318 -0.9525)
			(stroke
				(width 0)
				(type default)
			)
			(fill no)
			(layer "F.CrtYd")
		)
		(fp_rect
			(start -0.4318 0.9525)
			(end 0.4318 -0.9525)
			(stroke
				(width 0)
				(type default)
			)
			(fill no)
			(layer "F.Fab")
		)
		(pad "1" smd custom
			(at 0 -0.4445 270)
			(size 0.1524 0.1524)
			(layers "F.Cu" "F.Mask" "F.Paste")
			(net "P1V5_E_CC_R")
			(options
				(clearance outline)
				(anchor circle)
			)
			(primitives
				(gr_poly
					(pts
						(arc
							(start 0.3048 -0.2032)
							(mid 0.275042 -0.275042)
							(end 0.2032 -0.3048)
						)
						(arc
							(start -0.2032 -0.3048)
							(mid -0.275042 -0.275042)
							(end -0.3048 -0.2032)
						)
						(arc
							(start -0.3048 0.2032)
							(mid -0.275042 0.275042)
							(end -0.2032 0.3048)
						)
						(arc
							(start 0.2032 0.3048)
							(mid 0.275042 0.275042)
							(end 0.3048 0.2032)
						)
					)
					(width 0)
					(fill yes)
				)
			)
		)
		(pad "2" smd custom
			(at 0 0.4445 270)
			(size 0.1524 0.1524)
			(layers "F.Cu" "F.Mask" "F.Paste")
			(net "P1V5_E_VFB")
			(options
				(clearance outline)
				(anchor circle)
			)
			(primitives
				(gr_poly
					(pts
						(arc
							(start 0.3048 -0.2032)
							(mid 0.275042 -0.275042)
							(end 0.2032 -0.3048)
						)
						(arc
							(start -0.2032 -0.3048)
							(mid -0.275042 -0.275042)
							(end -0.3048 -0.2032)
						)
						(arc
							(start -0.3048 0.2032)
							(mid -0.275042 0.275042)
							(end -0.2032 0.3048)
						)
						(arc
							(start 0.2032 0.3048)
							(mid 0.275042 0.275042)
							(end 0.3048 0.2032)
						)
					)
					(width 0)
					(fill yes)
				)
			)
		)
	)
	(footprint ""
		(layer "F.Cu")
		(at 318.008 -165.354 -90)
		(property "Reference" "R249"
			(at 0 0 270)
			(layer "F.SilkS")
			(hide yes)
			(effects
				(font
					(size 1.27 1.27)
				)
			)
		)
		(property "Value" "0R2J-2-GP"
			(at 0.064008 -3.993896 270)
			(unlocked yes)
			(layer "F.Fab")
			(hide yes)
			(effects
				(font
					(size 1.016 1.016)
					(thickness 0.1524)
				)
			)
		)
		(property "Device Type" "R402H16"
			(at 0.064008 -5.517896 270)
			(unlocked yes)
			(layer "F.Fab")
			(hide yes)
			(effects
				(font
					(size 1.016 1.016)
					(thickness 0.1524)
				)
			)
		)
		(duplicate_pad_numbers_are_jumpers no)
		(fp_line
			(start -0.508 -0.9398)
			(end -0.508 0.9398)
			(stroke
				(width 0.1524)
				(type default)
			)
			(layer "F.SilkS")
		)
		(fp_line
			(start 0.508 -0.9398)
			(end -0.508 -0.9398)
			(stroke
				(width 0.1524)
				(type default)
			)
			(layer "F.SilkS")
		)
		(fp_rect
			(start -0.508 0.9398)
			(end 0.508 -0.9398)
			(stroke
				(width 0)
				(type default)
			)
			(fill no)
			(layer "F.CrtYd")
		)
		(fp_rect
			(start -0.508 0.9398)
			(end 0.508 -0.9398)
			(stroke
				(width 0)
				(type default)
			)
			(fill no)
			(layer "F.Fab")
		)
		(pad "1" smd custom
			(at 0 -0.4445 270)
			(size 0.1397 0.1397)
			(layers "F.Cu" "F.Mask" "F.Paste")
			(net "BMC_I2C_C_SCL")
			(options
				(clearance outline)
				(anchor circle)
			)
			(primitives
				(gr_poly
					(pts
						(arc
							(start -0.1778 -0.2794)
							(mid -0.249642 -0.249642)
							(end -0.2794 -0.1778)
						)
						(arc
							(start -0.2794 0.1778)
							(mid -0.249642 0.249642)
							(end -0.1778 0.2794)
						)
						(arc
							(start 0.1778 0.2794)
							(mid 0.249642 0.249642)
							(end 0.2794 0.1778)
						)
						(arc
							(start 0.2794 -0.1778)
							(mid 0.249642 -0.249642)
							(end 0.1778 -0.2794)
						)
					)
					(width 0)
					(fill yes)
				)
			)
		)
		(pad "2" smd custom
			(at 0 0.4445 270)
			(size 0.1397 0.1397)
			(layers "F.Cu" "F.Mask" "F.Paste")
			(net "BMC0_SMB6_CLK")
			(options
				(clearance outline)
				(anchor circle)
			)
			(primitives
				(gr_poly
					(pts
						(arc
							(start -0.1778 -0.2794)
							(mid -0.249642 -0.249642)
							(end -0.2794 -0.1778)
						)
						(arc
							(start -0.2794 0.1778)
							(mid -0.249642 0.249642)
							(end -0.1778 0.2794)
						)
						(arc
							(start 0.1778 0.2794)
							(mid 0.249642 0.249642)
							(end 0.2794 0.1778)
						)
						(arc
							(start 0.2794 -0.1778)
							(mid 0.249642 -0.249642)
							(end 0.1778 -0.2794)
						)
					)
					(width 0)
					(fill yes)
				)
			)
		)
	)
	(footprint ""
		(layer "F.Cu")
		(at 305.816 -191.262 -90)
		(property "Reference" "C89"
			(at 0 0 270)
			(layer "F.SilkS")
			(hide yes)
			(effects
				(font
					(size 1.27 1.27)
				)
			)
		)
		(property "Value" "SCD1U16V2KX-3GP"
			(at 1.1811 -2.7051 270)
			(unlocked yes)
			(layer "F.Fab")
			(hide yes)
			(effects
				(font
					(size 1.016 1.016)
					(thickness 0.1524)
				)
			)
		)
		(property "Device Type" "C402H22"
			(at 1.1811 -4.2291 270)
			(unlocked yes)
			(layer "F.Fab")
			(hide yes)
			(effects
				(font
					(size 1.016 1.016)
					(thickness 0.1524)
				)
			)
		)
		(duplicate_pad_numbers_are_jumpers no)
		(fp_rect
			(start -0.4318 0.9525)
			(end 0.4318 -0.9525)
			(stroke
				(width 0)
				(type default)
			)
			(fill no)
			(layer "F.CrtYd")
		)
		(fp_rect
			(start -0.4318 0.9525)
			(end 0.4318 -0.9525)
			(stroke
				(width 0)
				(type default)
			)
			(fill no)
			(layer "F.Fab")
		)
		(pad "1" smd custom
			(at 0 -0.4445 270)
			(size 0.1524 0.1524)
			(layers "F.Cu" "F.Mask" "F.Paste")
			(net "P3V3_STBY")
			(options
				(clearance outline)
				(anchor circle)
			)
			(primitives
				(gr_poly
					(pts
						(arc
							(start 0.3048 -0.2032)
							(mid 0.275042 -0.275042)
							(end 0.2032 -0.3048)
						)
						(arc
							(start -0.2032 -0.3048)
							(mid -0.275042 -0.275042)
							(end -0.3048 -0.2032)
						)
						(arc
							(start -0.3048 0.2032)
							(mid -0.275042 0.275042)
							(end -0.2032 0.3048)
						)
						(arc
							(start 0.2032 0.3048)
							(mid 0.275042 0.275042)
							(end 0.3048 0.2032)
						)
					)
					(width 0)
					(fill yes)
				)
			)
		)
		(pad "2" smd custom
			(at 0 0.4445 270)
			(size 0.1524 0.1524)
			(layers "F.Cu" "F.Mask" "F.Paste")
			(net "GND")
			(options
				(clearance outline)
				(anchor circle)
			)
			(primitives
				(gr_poly
					(pts
						(arc
							(start 0.3048 -0.2032)
							(mid 0.275042 -0.275042)
							(end 0.2032 -0.3048)
						)
						(arc
							(start -0.2032 -0.3048)
							(mid -0.275042 -0.275042)
							(end -0.3048 -0.2032)
						)
						(arc
							(start -0.3048 0.2032)
							(mid -0.275042 0.275042)
							(end -0.2032 0.3048)
						)
						(arc
							(start 0.2032 0.3048)
							(mid 0.275042 0.275042)
							(end 0.3048 0.2032)
						)
					)
					(width 0)
					(fill yes)
				)
			)
		)
	)
	(footprint ""
		(layer "F.Cu")
		(at 275.708872 -225.116136 180)
		(property "Reference" "PC80"
			(at 0 0 180)
			(layer "F.SilkS")
			(hide yes)
			(effects
				(font
					(size 1.27 1.27)
				)
			)
		)
		(property "Value" "SC10U6D3V5KX-1GP"
			(at -0.0762 -6.1214 180)
			(unlocked yes)
			(layer "F.Fab")
			(hide yes)
			(effects
				(font
					(size 1.016 1.016)
					(thickness 0.1524)
				)
			)
		)
		(property "Device Type" "C805H54"
			(at -0.0762 -8.1534 180)
			(unlocked yes)
			(layer "F.Fab")
			(hide yes)
			(effects
				(font
					(size 1.016 1.016)
					(thickness 0.1524)
				)
			)
		)
		(duplicate_pad_numbers_are_jumpers no)
		(fp_line
			(start 0.635 0)
			(end -0.635 0)
			(stroke
				(width 0.508)
				(type default)
			)
			(layer "F.SilkS")
		)
		(fp_rect
			(start -0.9652 1.778)
			(end 0.9652 -1.778)
			(stroke
				(width 0)
				(type default)
			)
			(fill no)
			(layer "F.CrtYd")
		)
		(fp_poly
			(pts
				(xy -0.9652 -1.778) (xy 0.9652 -1.778) (xy 0.9652 1.778) (xy -0.9652 1.778)
			)
			(stroke
				(width 0)
				(type default)
			)
			(fill no)
			(layer "F.Fab")
		)
		(pad "1" smd rect
			(at 0 -0.9652 180)
			(size 1.397 1.143)
			(layers "F.Cu" "F.Mask" "F.Paste")
			(net "TPS74801_P1V53_STBY_IN")
		)
		(pad "2" smd rect
			(at 0 0.9652 180)
			(size 1.397 1.143)
			(layers "F.Cu" "F.Mask" "F.Paste")
			(net "GND")
		)
	)
)
